# T6G (Grand Teton) — schematic netlist excerpt (pin names and nets, part order shuffled) for the footprints in the layout excerpt that follows; sources: Cadence DE-HDL packaged netlist, KiCad conversion of 04192023_DAF0TMB3IC0_F0TG_MB_C_brd_V02_OCP.brd

PR239  Q_RES  0 5% CHIP  pkg 0402LF  page 217 : A = SVID_PVDDCR_CPU1_P1_SVTI ; B = SVID_PVDDCR_CPU1_P1_SVTI_R
R3684  Q_RES  0 5% CHIP  pkg 0402LF  page 257 : A = P3V3_ADC ; B = P3V3_ADC_TIC
C881  Q_CAP_DIFFBUS  DIFF BUS_0.22UF 6.3V 20% X6S  pkg C0201  page 64 : \1\ = P5E_CPU0_P3_TX_C_DP<10> ; \2\ = P5E_CPU0_P3_TX_DP<10>

(kicad_pcb
	(version 20260206)
	(generator "pcbnew")
	(generator_version "10.0")
	(general
		(thickness 1.6)
		(legacy_teardrops no)
	)
	(paper "A4")
	(title_block
		(title "04192023_DAF0TMB3IC0_F0TG_MB_C_brd_V02_OCP.brd")
		(comment 1 "Grand Teton / footprints 4322-4324 of 8354")
	)
	(layers
		(0 "F.Cu" signal "TOP")
		(4 "In1.Cu" signal "GND")
		(6 "In2.Cu" signal "IN1")
		(8 "In3.Cu" signal "GND1")
		(10 "In4.Cu" signal "IN2")
		(12 "In5.Cu" signal "GND2")
		(14 "In6.Cu" signal "IN3")
		(16 "In7.Cu" signal "GND3")
		(18 "In8.Cu" signal "VCC")
		(20 "In9.Cu" signal "VCC1")
		(22 "In10.Cu" signal "GND4")
		(24 "In11.Cu" signal "IN4")
		(26 "In12.Cu" signal "GND5")
		(28 "In13.Cu" signal "IN5")
		(30 "In14.Cu" signal "GND6")
		(32 "In15.Cu" signal "IN6")
		(34 "In16.Cu" signal "GND7")
		(2 "B.Cu" signal "BOTTOM")
		(9 "F.Adhes" user "F.Adhesive")
		(11 "B.Adhes" user "B.Adhesive")
		(13 "F.Paste" user "Package Geometry/Pastemask Top")
		(15 "B.Paste" user "Package Geometry/Pastemask Bottom")
		(5 "F.SilkS" user "Ref Des/Silkscreen Top")
		(7 "B.SilkS" user "Ref Des/Silkscreen Bottom")
		(1 "F.Mask" user "Board Geometry/Soldermask Top")
		(3 "B.Mask" user "Board Geometry/Soldermask Bottom")
		(17 "Dwgs.User" user "User.Drawings")
		(19 "Cmts.User" user "User.Comments")
		(21 "Eco1.User" user "User.Eco1")
		(23 "Eco2.User" user "User.Eco2")
		(25 "Edge.Cuts" user "Board Geometry/Outline")
		(27 "Margin" user)
		(31 "F.CrtYd" user "Package Geometry/Place Bound Top")
		(29 "B.CrtYd" user "Package Geometry/Place Bound Bottom")
		(35 "F.Fab" user "Ref Des/Assembly Top")
		(33 "B.Fab" user "Ref Des/Assembly Bottom")
	)
	(footprint ""
		(layer "F.Cu")
		(at 322.837048 -42.176954 180)
		(property "Reference" "R3684"
			(at 0 0 180)
			(layer "F.SilkS")
			(hide yes)
			(effects
				(font
					(size 1.27 1.27)
				)
			)
		)
		(property "Value" ""
			(at 0 0 180)
			(layer "F.Fab")
			(effects
				(font
					(size 1.27 1.27)
				)
			)
		)
		(duplicate_pad_numbers_are_jumpers no)
		(fp_line
			(start 0.7874 0.4064)
			(end -0.7874 0.4064)
			(stroke
				(width 0.1524)
				(type default)
			)
			(layer "F.SilkS")
		)
		(fp_line
			(start 0.7874 -0.4064)
			(end 0.7874 0.4064)
			(stroke
				(width 0.1524)
				(type default)
			)
			(layer "F.SilkS")
		)
		(fp_line
			(start -0.7874 0.4064)
			(end -0.7874 -0.4064)
			(stroke
				(width 0.1524)
				(type default)
			)
			(layer "F.SilkS")
		)
		(fp_line
			(start -0.7874 -0.4064)
			(end 0.7874 -0.4064)
			(stroke
				(width 0.1524)
				(type default)
			)
			(layer "F.SilkS")
		)
		(fp_line
			(start 0.67945 0.3048)
			(end 0.120396 0.3048)
			(stroke
				(width 0.1)
				(type default)
			)
			(layer "F.Fab")
		)
		(fp_line
			(start 0.67945 -0.3048)
			(end 0.67945 0.3048)
			(stroke
				(width 0.1)
				(type default)
			)
			(layer "F.Fab")
		)
		(fp_line
			(start 0.12065 -0.2794)
			(end 0.12065 -0.3048)
			(stroke
				(width 0.1)
				(type default)
			)
			(layer "F.Fab")
		)
		(fp_line
			(start 0.12065 -0.3048)
			(end 0.67945 -0.3048)
			(stroke
				(width 0.1)
				(type default)
			)
			(layer "F.Fab")
		)
		(fp_line
			(start 0.120396 0.3048)
			(end 0.120396 0.2794)
			(stroke
				(width 0.1)
				(type default)
			)
			(layer "F.Fab")
		)
		(fp_line
			(start 0.120396 0.2794)
			(end -0.12065 0.2794)
			(stroke
				(width 0.1)
				(type default)
			)
			(layer "F.Fab")
		)
		(fp_line
			(start -0.12065 0.3048)
			(end -0.67945 0.3048)
			(stroke
				(width 0.1)
				(type default)
			)
			(layer "F.Fab")
		)
		(fp_line
			(start -0.12065 0.2794)
			(end -0.12065 0.3048)
			(stroke
				(width 0.1)
				(type default)
			)
			(layer "F.Fab")
		)
		(fp_line
			(start -0.12065 -0.2794)
			(end 0.12065 -0.2794)
			(stroke
				(width 0.1)
				(type default)
			)
			(layer "F.Fab")
		)
		(fp_line
			(start -0.12065 -0.305054)
			(end -0.12065 -0.2794)
			(stroke
				(width 0.1)
				(type default)
			)
			(layer "F.Fab")
		)
		(fp_line
			(start -0.67945 0.3048)
			(end -0.67945 -0.305054)
			(stroke
				(width 0.1)
				(type default)
			)
			(layer "F.Fab")
		)
		(fp_line
			(start -0.67945 -0.305054)
			(end -0.12065 -0.305054)
			(stroke
				(width 0.1)
				(type default)
			)
			(layer "F.Fab")
		)
		(pad "1" smd rect
			(at -0.40005 0)
			(size 0.4572 0.508)
			(layers "F.Cu" "F.Mask" "F.Paste")
			(net "P3V3_ADC")
		)
		(pad "2" smd rect
			(at 0.40005 0)
			(size 0.4572 0.508)
			(layers "F.Cu" "F.Mask" "F.Paste")
			(net "P3V3_ADC_TIC")
		)
	)
	(footprint ""
		(layer "F.Cu")
		(at 24.765 -357.632)
		(property "Reference" "PR239"
			(at 0 0 0)
			(layer "F.SilkS")
			(hide yes)
			(effects
				(font
					(size 1.27 1.27)
				)
			)
		)
		(property "Value" ""
			(at 0 0 0)
			(layer "F.Fab")
			(effects
				(font
					(size 1.27 1.27)
				)
			)
		)
		(duplicate_pad_numbers_are_jumpers no)
		(fp_line
			(start -0.7874 -0.4064)
			(end 0.7874 -0.4064)
			(stroke
				(width 0.1524)
				(type default)
			)
			(layer "F.SilkS")
		)
		(fp_line
			(start -0.7874 0.4064)
			(end -0.7874 -0.4064)
			(stroke
				(width 0.1524)
				(type default)
			)
			(layer "F.SilkS")
		)
		(fp_line
			(start 0.7874 -0.4064)
			(end 0.7874 0.4064)
			(stroke
				(width 0.1524)
				(type default)
			)
			(layer "F.SilkS")
		)
		(fp_line
			(start 0.7874 0.4064)
			(end -0.7874 0.4064)
			(stroke
				(width 0.1524)
				(type default)
			)
			(layer "F.SilkS")
		)
		(fp_line
			(start -0.67945 -0.305054)
			(end -0.12065 -0.305054)
			(stroke
				(width 0.1)
				(type default)
			)
			(layer "F.Fab")
		)
		(fp_line
			(start -0.67945 0.3048)
			(end -0.67945 -0.305054)
			(stroke
				(width 0.1)
				(type default)
			)
			(layer "F.Fab")
		)
		(fp_line
			(start -0.12065 -0.305054)
			(end -0.12065 -0.2794)
			(stroke
				(width 0.1)
				(type default)
			)
			(layer "F.Fab")
		)
		(fp_line
			(start -0.12065 -0.2794)
			(end 0.12065 -0.2794)
			(stroke
				(width 0.1)
				(type default)
			)
			(layer "F.Fab")
		)
		(fp_line
			(start -0.12065 0.2794)
			(end -0.12065 0.3048)
			(stroke
				(width 0.1)
				(type default)
			)
			(layer "F.Fab")
		)
		(fp_line
			(start -0.12065 0.3048)
			(end -0.67945 0.3048)
			(stroke
				(width 0.1)
				(type default)
			)
			(layer "F.Fab")
		)
		(fp_line
			(start 0.120396 0.2794)
			(end -0.12065 0.2794)
			(stroke
				(width 0.1)
				(type default)
			)
			(layer "F.Fab")
		)
		(fp_line
			(start 0.120396 0.3048)
			(end 0.120396 0.2794)
			(stroke
				(width 0.1)
				(type default)
			)
			(layer "F.Fab")
		)
		(fp_line
			(start 0.12065 -0.3048)
			(end 0.67945 -0.3048)
			(stroke
				(width 0.1)
				(type default)
			)
			(layer "F.Fab")
		)
		(fp_line
			(start 0.12065 -0.2794)
			(end 0.12065 -0.3048)
			(stroke
				(width 0.1)
				(type default)
			)
			(layer "F.Fab")
		)
		(fp_line
			(start 0.67945 -0.3048)
			(end 0.67945 0.3048)
			(stroke
				(width 0.1)
				(type default)
			)
			(layer "F.Fab")
		)
		(fp_line
			(start 0.67945 0.3048)
			(end 0.120396 0.3048)
			(stroke
				(width 0.1)
				(type default)
			)
			(layer "F.Fab")
		)
		(pad "1" smd circle
			(at -0.40005 0)
			(size 0 0)
			(layers "F.Cu" "F.Mask" "F.Paste")
			(net "SVID_PVDDCR_CPU1_P1_SVTI")
		)
		(pad "2" smd circle
			(at 0.40005 0)
			(size 0 0)
			(layers "F.Cu" "F.Mask" "F.Paste")
			(net "SVID_PVDDCR_CPU1_P1_SVTI_R")
		)
	)
	(footprint ""
		(layer "F.Cu")
		(at 384.809492 -383.88163 -90)
		(property "Reference" "C881"
			(at 0 0 270)
			(layer "F.SilkS")
			(hide yes)
			(effects
				(font
					(size 1.27 1.27)
				)
			)
		)
		(property "Value" ""
			(at 0 0 270)
			(layer "F.Fab")
			(effects
				(font
					(size 1.27 1.27)
				)
			)
		)
		(duplicate_pad_numbers_are_jumpers no)
		(fp_line
			(start -0.299974 0.150114)
			(end -0.299974 -0.150114)
			(stroke
				(width 0.1)
				(type default)
			)
			(layer "F.Fab")
		)
		(fp_line
			(start 0.299974 0.150114)
			(end -0.299974 0.150114)
			(stroke
				(width 0.1)
				(type default)
			)
			(layer "F.Fab")
		)
		(fp_line
			(start -0.299974 -0.150114)
			(end 0.299974 -0.150114)
			(stroke
				(width 0.1)
				(type default)
			)
			(layer "F.Fab")
		)
		(fp_line
			(start 0.299974 -0.150114)
			(end 0.299974 0.150114)
			(stroke
				(width 0.1)
				(type default)
			)
			(layer "F.Fab")
		)
		(pad "1" smd rect
			(at -0.2667 0 270)
			(size 0.3048 0.381)
			(layers "F.Cu" "F.Mask" "F.Paste")
			(net "P5E_CPU0_P3_TX_C_DP<10>")
		)
		(pad "2" smd rect
			(at 0.2667 0 270)
			(size 0.3048 0.381)
			(layers "F.Cu" "F.Mask" "F.Paste")
			(net "P5E_CPU0_P3_TX_DP<10>")
		)
	)
)
